# S9S_MB_2U (Grand Teton) — schematic netlist excerpt (pin names and nets, part order shuffled) for the footprints in the layout excerpt that follows; sources: Cadence DE-HDL packaged netlist, KiCad conversion of 03242023_DA0F0TMBIJ0_F0T_Motherboard_J_brd_V01_OCP.brd

PC469  Q_CAP  3300PF 50V 10% X7R  pkg 0402  page 292 : A = SH_PVCCFA_EHV_CPU1_R ; B = VSENSE_PVCCFA_EHV_CPU1_DN
C1862  Q_CAP  0.1UF 25V 10% X7R  pkg 0402  page 238 : A = P3V3_OCP_SFF ; B = GND

(kicad_pcb
	(version 20260206)
	(generator "pcbnew")
	(generator_version "10.0")
	(general
		(thickness 1.6)
		(legacy_teardrops no)
	)
	(paper "A4")
	(title_block
		(title "03242023_DA0F0TMBIJ0_F0T_Motherboard_J_brd_V01_OCP.brd")
		(comment 1 "Grand Teton / footprints 81-82 of 6105")
	)
	(layers
		(0 "F.Cu" signal "TOP")
		(4 "In1.Cu" signal "GND")
		(6 "In2.Cu" signal "IN1")
		(8 "In3.Cu" signal "GND1")
		(10 "In4.Cu" signal "IN2")
		(12 "In5.Cu" signal "GND2")
		(14 "In6.Cu" signal "IN3")
		(16 "In7.Cu" signal "GND3")
		(18 "In8.Cu" signal "VCC")
		(20 "In9.Cu" signal "VCC1")
		(22 "In10.Cu" signal "GND4")
		(24 "In11.Cu" signal "IN4")
		(26 "In12.Cu" signal "GND5")
		(28 "In13.Cu" signal "IN5")
		(30 "In14.Cu" signal "GND6")
		(32 "In15.Cu" signal "IN6")
		(34 "In16.Cu" signal "GND7")
		(2 "B.Cu" signal "BOTTOM")
		(9 "F.Adhes" user "F.Adhesive")
		(11 "B.Adhes" user "B.Adhesive")
		(13 "F.Paste" user "Package Geometry/Pastemask Top")
		(15 "B.Paste" user "Package Geometry/Pastemask Bottom")
		(5 "F.SilkS" user "Ref Des/Silkscreen Top")
		(7 "B.SilkS" user "Ref Des/Silkscreen Bottom")
		(1 "F.Mask" user "Board Geometry/Soldermask Top")
		(3 "B.Mask" user "Board Geometry/Soldermask Bottom")
		(17 "Dwgs.User" user "User.Drawings")
		(19 "Cmts.User" user "User.Comments")
		(21 "Eco1.User" user "User.Eco1")
		(23 "Eco2.User" user "User.Eco2")
		(25 "Edge.Cuts" user "Board Geometry/Outline")
		(27 "Margin" user)
		(31 "F.CrtYd" user "Package Geometry/Place Bound Top")
		(29 "B.CrtYd" user "Package Geometry/Place Bound Bottom")
		(35 "F.Fab" user "Ref Des/Assembly Top")
		(33 "B.Fab" user "Ref Des/Assembly Bottom")
	)
	(footprint ""
		(layer "F.Cu")
		(at 445.175386 -47.627286 180)
		(property "Reference" "C1862"
			(at 0 0 180)
			(layer "F.SilkS")
			(hide yes)
			(effects
				(font
					(size 1.27 1.27)
				)
			)
		)
		(property "Value" ""
			(at 0 0 180)
			(layer "F.Fab")
			(effects
				(font
					(size 1.27 1.27)
				)
			)
		)
		(duplicate_pad_numbers_are_jumpers no)
		(fp_line
			(start 0.7874 0.4064)
			(end -0.7874 0.4064)
			(stroke
				(width 0.1524)
				(type default)
			)
			(layer "F.SilkS")
		)
		(fp_line
			(start 0.7874 -0.4064)
			(end 0.7874 0.4064)
			(stroke
				(width 0.1524)
				(type default)
			)
			(layer "F.SilkS")
		)
		(fp_line
			(start -0.7874 0.4064)
			(end -0.7874 -0.4064)
			(stroke
				(width 0.1524)
				(type default)
			)
			(layer "F.SilkS")
		)
		(fp_line
			(start -0.7874 -0.4064)
			(end 0.7874 -0.4064)
			(stroke
				(width 0.1524)
				(type default)
			)
			(layer "F.SilkS")
		)
		(fp_line
			(start 0.67945 0.3048)
			(end 0.120396 0.3048)
			(stroke
				(width 0.1)
				(type default)
			)
			(layer "F.Fab")
		)
		(fp_line
			(start 0.67945 -0.3048)
			(end 0.67945 0.3048)
			(stroke
				(width 0.1)
				(type default)
			)
			(layer "F.Fab")
		)
		(fp_line
			(start 0.12065 -0.2794)
			(end 0.12065 -0.3048)
			(stroke
				(width 0.1)
				(type default)
			)
			(layer "F.Fab")
		)
		(fp_line
			(start 0.12065 -0.3048)
			(end 0.67945 -0.3048)
			(stroke
				(width 0.1)
				(type default)
			)
			(layer "F.Fab")
		)
		(fp_line
			(start 0.120396 0.3048)
			(end 0.120396 0.2794)
			(stroke
				(width 0.1)
				(type default)
			)
			(layer "F.Fab")
		)
		(fp_line
			(start 0.120396 0.2794)
			(end -0.12065 0.2794)
			(stroke
				(width 0.1)
				(type default)
			)
			(layer "F.Fab")
		)
		(fp_line
			(start -0.12065 0.3048)
			(end -0.67945 0.3048)
			(stroke
				(width 0.1)
				(type default)
			)
			(layer "F.Fab")
		)
		(fp_line
			(start -0.12065 0.2794)
			(end -0.12065 0.3048)
			(stroke
				(width 0.1)
				(type default)
			)
			(layer "F.Fab")
		)
		(fp_line
			(start -0.12065 -0.2794)
			(end 0.12065 -0.2794)
			(stroke
				(width 0.1)
				(type default)
			)
			(layer "F.Fab")
		)
		(fp_line
			(start -0.12065 -0.305054)
			(end -0.12065 -0.2794)
			(stroke
				(width 0.1)
				(type default)
			)
			(layer "F.Fab")
		)
		(fp_line
			(start -0.67945 0.3048)
			(end -0.67945 -0.305054)
			(stroke
				(width 0.1)
				(type default)
			)
			(layer "F.Fab")
		)
		(fp_line
			(start -0.67945 -0.305054)
			(end -0.12065 -0.305054)
			(stroke
				(width 0.1)
				(type default)
			)
			(layer "F.Fab")
		)
		(pad "1" smd circle
			(at -0.40005 0 180)
			(size 0 0)
			(layers "F.Cu" "F.Mask" "F.Paste")
			(net "P3V3_OCP_SFF")
		)
		(pad "2" smd circle
			(at 0.40005 0 180)
			(size 0 0)
			(layers "F.Cu" "F.Mask" "F.Paste")
			(net "GND")
		)
	)
	(footprint ""
		(layer "F.Cu")
		(at 29.035756 -133.04139)
		(property "Reference" "PC469"
			(at 0 0 0)
			(layer "F.SilkS")
			(hide yes)
			(effects
				(font
					(size 1.27 1.27)
				)
			)
		)
		(property "Value" ""
			(at 0 0 0)
			(layer "F.Fab")
			(effects
				(font
					(size 1.27 1.27)
				)
			)
		)
		(duplicate_pad_numbers_are_jumpers no)
		(fp_line
			(start -0.7874 -0.4064)
			(end 0.7874 -0.4064)
			(stroke
				(width 0.1524)
				(type default)
			)
			(layer "F.SilkS")
		)
		(fp_line
			(start -0.7874 0.4064)
			(end -0.7874 -0.4064)
			(stroke
				(width 0.1524)
				(type default)
			)
			(layer "F.SilkS")
		)
		(fp_line
			(start 0.7874 -0.4064)
			(end 0.7874 0.4064)
			(stroke
				(width 0.1524)
				(type default)
			)
			(layer "F.SilkS")
		)
		(fp_line
			(start 0.7874 0.4064)
			(end -0.7874 0.4064)
			(stroke
				(width 0.1524)
				(type default)
			)
			(layer "F.SilkS")
		)
		(fp_line
			(start -0.67945 -0.305054)
			(end -0.12065 -0.305054)
			(stroke
				(width 0.1)
				(type default)
			)
			(layer "F.Fab")
		)
		(fp_line
			(start -0.67945 0.3048)
			(end -0.67945 -0.305054)
			(stroke
				(width 0.1)
				(type default)
			)
			(layer "F.Fab")
		)
		(fp_line
			(start -0.12065 -0.305054)
			(end -0.12065 -0.2794)
			(stroke
				(width 0.1)
				(type default)
			)
			(layer "F.Fab")
		)
		(fp_line
			(start -0.12065 -0.2794)
			(end 0.12065 -0.2794)
			(stroke
				(width 0.1)
				(type default)
			)
			(layer "F.Fab")
		)
		(fp_line
			(start -0.12065 0.2794)
			(end -0.12065 0.3048)
			(stroke
				(width 0.1)
				(type default)
			)
			(layer "F.Fab")
		)
		(fp_line
			(start -0.12065 0.3048)
			(end -0.67945 0.3048)
			(stroke
				(width 0.1)
				(type default)
			)
			(layer "F.Fab")
		)
		(fp_line
			(start 0.120396 0.2794)
			(end -0.12065 0.2794)
			(stroke
				(width 0.1)
				(type default)
			)
			(layer "F.Fab")
		)
		(fp_line
			(start 0.120396 0.3048)
			(end 0.120396 0.2794)
			(stroke
				(width 0.1)
				(type default)
			)
			(layer "F.Fab")
		)
		(fp_line
			(start 0.12065 -0.3048)
			(end 0.67945 -0.3048)
			(stroke
				(width 0.1)
				(type default)
			)
			(layer "F.Fab")
		)
		(fp_line
			(start 0.12065 -0.2794)
			(end 0.12065 -0.3048)
			(stroke
				(width 0.1)
				(type default)
			)
			(layer "F.Fab")
		)
		(fp_line
			(start 0.67945 -0.3048)
			(end 0.67945 0.3048)
			(stroke
				(width 0.1)
				(type default)
			)
			(layer "F.Fab")
		)
		(fp_line
			(start 0.67945 0.3048)
			(end 0.120396 0.3048)
			(stroke
				(width 0.1)
				(type default)
			)
			(layer "F.Fab")
		)
		(pad "1" smd circle
			(at -0.40005 0)
			(size 0 0)
			(layers "F.Cu" "F.Mask" "F.Paste")
			(net "SH_PVCCFA_EHV_CPU1_R")
		)
		(pad "2" smd circle
			(at 0.40005 0)
			(size 0 0)
			(layers "F.Cu" "F.Mask" "F.Paste")
			(net "VSENSE_PVCCFA_EHV_CPU1_DN")
		)
	)
)
